(kicad_pcb
	(version 20241229)
	(generator "pcbnew")
	(generator_version "9.0")
	(general
		(thickness 1.294)
		(legacy_teardrops no)
	)
	(paper "A3")
	(title_block
		(title "Kintex 410T devboard")
		(date "2024-04-03")
		(rev "1.1.2")
		(comment 9 "footprints 752-758 of 975")
	)
	(layers
		(0 "F.Cu" mixed)
		(4 "In1.Cu" power)
		(6 "In2.Cu" power)
		(8 "In3.Cu" mixed)
		(10 "In4.Cu" power)
		(12 "In5.Cu" mixed)
		(14 "In6.Cu" power)
		(16 "In7.Cu" mixed)
		(18 "In8.Cu" power)
		(2 "B.Cu" mixed)
		(9 "F.Adhes" user "F.Adhesive")
		(11 "B.Adhes" user "B.Adhesive")
		(13 "F.Paste" user)
		(15 "B.Paste" user)
		(5 "F.SilkS" user "F.Silkscreen")
		(7 "B.SilkS" user "B.Silkscreen")
		(1 "F.Mask" user)
		(3 "B.Mask" user)
		(17 "Dwgs.User" user "User.Drawings")
		(19 "Cmts.User" user "User.Comments")
		(21 "Eco1.User" user "User.Eco1")
		(23 "Eco2.User" user "User.Eco2")
		(25 "Edge.Cuts" user)
		(27 "Margin" user)
		(31 "F.CrtYd" user "F.Courtyard")
		(29 "B.CrtYd" user "B.Courtyard")
		(35 "F.Fab" user)
		(33 "B.Fab" user)
	)
	(footprint "antmicro-footprints:R_0402_1005Metric"
		(layer "B.Cu")
		(at 221.999999 77.899999 -90)
		(descr "Resistor SMD 0402")
		(tags "resistor SMD 0402")
		(property "Reference" "R123"
			(at -3.599999 -0.350001 90)
			(layer "B.SilkS")
			(effects
				(font
					(size 0.7 0.7)
					(thickness 0.15)
				)
				(justify left bottom mirror)
			)
		)
		(property "Value" "R_100R_0402"
			(at 0 -1.4 90)
			(layer "B.Fab")
			(effects
				(font
					(size 0.7 0.7)
					(thickness 0.15)
				)
				(justify left bottom mirror)
			)
		)
		(property "Description" "SMD Chip Resistor, 100 ohm, ± 1%, 62.5 mW, 0402 [1005 Metric], Thick Film, General Purpose"
			(at 0 0 270)
			(layer "F.Fab")
			(hide yes)
			(effects
				(font
					(size 1.27 1.27)
					(thickness 0.15)
				)
			)
		)
		(property "Author" "Antmicro"
			(at 144.1 299.899998 0)
			(layer "B.Fab")
			(hide yes)
			(effects
				(font
					(size 1 1)
					(thickness 0.15)
				)
				(justify mirror)
			)
		)
		(property "License" "Apache-2.0"
			(at 144.1 299.899998 0)
			(layer "B.Fab")
			(hide yes)
			(effects
				(font
					(size 1 1)
					(thickness 0.15)
				)
				(justify mirror)
			)
		)
		(property "MPN" "CR0402-FX-1000GLF"
			(at 144.1 299.899998 0)
			(layer "B.Fab")
			(hide yes)
			(effects
				(font
					(size 1 1)
					(thickness 0.15)
				)
				(justify mirror)
			)
		)
		(property "Manufacturer" "Bourns"
			(at 144.1 299.899998 0)
			(layer "B.Fab")
			(hide yes)
			(effects
				(font
					(size 1 1)
					(thickness 0.15)
				)
				(justify mirror)
			)
		)
		(property "Tolerance" "1%"
			(at 144.1 299.899998 0)
			(layer "B.Fab")
			(hide yes)
			(effects
				(font
					(size 1 1)
					(thickness 0.15)
				)
				(justify mirror)
			)
		)
		(property "Val" "100R"
			(at 144.1 299.899998 0)
			(layer "B.Fab")
			(hide yes)
			(effects
				(font
					(size 1 1)
					(thickness 0.15)
				)
				(justify mirror)
			)
		)
		(sheetname "User GPIO + LED + button + DIP switch")
		(sheetfile "user-gpio.kicad_sch")
		(attr smd)
		(fp_rect
			(start -0.925 0.47)
			(end 0.925 -0.47)
			(stroke
				(width 0.05)
				(type default)
			)
			(fill no)
			(layer "B.CrtYd")
		)
		(fp_rect
			(start -0.5 0.25)
			(end 0.5 -0.25)
			(stroke
				(width 0.15)
				(type solid)
			)
			(fill no)
			(layer "B.Fab")
		)
		(pad "1" smd roundrect
			(at -0.48 0 270)
			(size 0.59 0.64)
			(layers "B.Cu" "B.Mask" "B.Paste")
			(roundrect_rratio 0.25)
			(net 461 "/FPGA Bank 12 & 13/PMOD_A.IO4")
			(pintype "passive")
		)
		(pad "2" smd roundrect
			(at 0.48 0 270)
			(size 0.59 0.64)
			(layers "B.Cu" "B.Mask" "B.Paste")
			(roundrect_rratio 0.25)
			(net 803 "/User GPIO + LED + button + DIP switch/PMOD_A_4")
			(pintype "passive")
		)
	)
	(footprint "antmicro-footprints:NetTie-2_SMD_Pad0.127mm"
		(layer "B.Cu")
		(at 250.101 148.4 -90)
		(descr "Net tie, 2 pin, 0.127mm  SMD pads")
		(tags "net tie")
		(property "Reference" "NT13"
			(at -0.128 1.345 90)
			(layer "B.SilkS")
			(hide yes)
			(effects
				(font
					(size 0.7 0.7)
					(thickness 0.15)
				)
				(justify left bottom mirror)
			)
		)
		(property "Value" "Net-Tie_2"
			(at 0 -1.199 90)
			(layer "B.Fab")
			(effects
				(font
					(size 0.7 0.7)
					(thickness 0.15)
				)
				(justify left bottom mirror)
			)
		)
		(property "Description" "Net tie, 2 pins"
			(at 0 0 270)
			(layer "F.Fab")
			(hide yes)
			(effects
				(font
					(size 1.27 1.27)
					(thickness 0.15)
				)
			)
		)
		(property "Author" "Antmicro"
			(at 101.701 398.501 0)
			(layer "B.Fab")
			(hide yes)
			(effects
				(font
					(size 1 1)
					(thickness 0.15)
				)
				(justify mirror)
			)
		)
		(property "License" "Apache-2.0"
			(at 101.701 398.501 0)
			(layer "B.Fab")
			(hide yes)
			(effects
				(font
					(size 1 1)
					(thickness 0.15)
				)
				(justify mirror)
			)
		)
		(property "MPN" ""
			(at 101.701 398.501 0)
			(layer "B.Fab")
			(hide yes)
			(effects
				(font
					(size 1 1)
					(thickness 0.15)
				)
				(justify mirror)
			)
		)
		(property "Manufacturer" ""
			(at 101.701 398.501 0)
			(layer "B.Fab")
			(hide yes)
			(effects
				(font
					(size 1 1)
					(thickness 0.15)
				)
				(justify mirror)
			)
		)
		(sheetname "FPGA Bank 14 & 15")
		(sheetfile "fpga-bank-14-15.kicad_sch")
		(attr exclude_from_pos_files)
		(net_tie_pad_groups "1, 2")
		(fp_poly
			(pts
				(xy -0.0635 0.0635) (xy 0.0625 0.0635) (xy 0.0625 -0.0635) (xy -0.0635 -0.0635)
			)
			(stroke
				(width 0)
				(type solid)
			)
			(fill yes)
			(layer "B.Cu")
		)
		(pad "1" smd roundrect
			(at -0.127 0 90)
			(size 0.127 0.127)
			(layers "B.Cu")
			(roundrect_rratio 0.5)
			(chamfer_ratio 0)
			(chamfer top_left bottom_left)
			(net 38 "/FPGA Bank 14 & 15/SYSTEM_FLASH.DQ0")
			(pinfunction "1")
			(pintype "passive")
		)
		(pad "2" smd roundrect
			(at 0.126 0 270)
			(size 0.127 0.127)
			(layers "B.Cu")
			(roundrect_rratio 0.5)
			(chamfer_ratio 0)
			(chamfer top_left bottom_left)
			(net 1326 "/SUP_MCU.FPGA_MISO")
			(pinfunction "2")
			(pintype "passive")
		)
	)
	(footprint "antmicro-footprints:R_0402_1005Metric"
		(layer "B.Cu")
		(at 186.800001 84.800001 90)
		(descr "Resistor SMD 0402")
		(tags "resistor SMD 0402")
		(property "Reference" "R134"
			(at -0.725 0.4 270)
			(layer "B.SilkS")
			(effects
				(font
					(size 0.7 0.7)
					(thickness 0.15)
				)
				(justify left bottom mirror)
			)
		)
		(property "Value" "R_100R_0402"
			(at 0 -1.4 270)
			(layer "B.Fab")
			(effects
				(font
					(size 0.7 0.7)
					(thickness 0.15)
				)
				(justify left bottom mirror)
			)
		)
		(property "Description" "SMD Chip Resistor, 100 ohm, ± 1%, 62.5 mW, 0402 [1005 Metric], Thick Film, General Purpose"
			(at 0 0 90)
			(layer "F.Fab")
			(hide yes)
			(effects
				(font
					(size 1.27 1.27)
					(thickness 0.15)
				)
			)
		)
		(property "Author" "Antmicro"
			(at 271.600002 -102 0)
			(layer "B.Fab")
			(hide yes)
			(effects
				(font
					(size 1 1)
					(thickness 0.15)
				)
				(justify mirror)
			)
		)
		(property "License" "Apache-2.0"
			(at 271.600002 -102 0)
			(layer "B.Fab")
			(hide yes)
			(effects
				(font
					(size 1 1)
					(thickness 0.15)
				)
				(justify mirror)
			)
		)
		(property "MPN" "CR0402-FX-1000GLF"
			(at 271.600002 -102 0)
			(layer "B.Fab")
			(hide yes)
			(effects
				(font
					(size 1 1)
					(thickness 0.15)
				)
				(justify mirror)
			)
		)
		(property "Manufacturer" "Bourns"
			(at 271.600002 -102 0)
			(layer "B.Fab")
			(hide yes)
			(effects
				(font
					(size 1 1)
					(thickness 0.15)
				)
				(justify mirror)
			)
		)
		(property "Tolerance" "1%"
			(at 271.600002 -102 0)
			(layer "B.Fab")
			(hide yes)
			(effects
				(font
					(size 1 1)
					(thickness 0.15)
				)
				(justify mirror)
			)
		)
		(property "Val" "100R"
			(at 271.600002 -102 0)
			(layer "B.Fab")
			(hide yes)
			(effects
				(font
					(size 1 1)
					(thickness 0.15)
				)
				(justify mirror)
			)
		)
		(sheetname "User GPIO + LED + button + DIP switch")
		(sheetfile "user-gpio.kicad_sch")
		(attr smd)
		(fp_rect
			(start -0.925 0.47)
			(end 0.925 -0.47)
			(stroke
				(width 0.05)
				(type default)
			)
			(fill no)
			(layer "B.CrtYd")
		)
		(fp_rect
			(start -0.5 0.25)
			(end 0.5 -0.25)
			(stroke
				(width 0.15)
				(type solid)
			)
			(fill no)
			(layer "B.Fab")
		)
		(pad "1" smd roundrect
			(at -0.48 0 90)
			(size 0.59 0.64)
			(layers "B.Cu" "B.Mask" "B.Paste")
			(roundrect_rratio 0.25)
			(net 823 "/User GPIO + LED + button + DIP switch/CW_20PIN_RST")
			(pintype "passive")
		)
		(pad "2" smd roundrect
			(at 0.48 0 90)
			(size 0.59 0.64)
			(layers "B.Cu" "B.Mask" "B.Paste")
			(roundrect_rratio 0.25)
			(net 474 "/FPGA Bank 12 & 13/CW_HEADER.RST")
			(pintype "passive")
		)
	)
	(footprint "antmicro-footprints:R_0402_1005Metric"
		(layer "B.Cu")
		(at 261.5 88.6)
		(descr "Resistor SMD 0402")
		(tags "resistor SMD 0402")
		(property "Reference" "R109"
			(at 1.375 1.275 180)
			(layer "B.SilkS")
			(effects
				(font
					(size 0.7 0.7)
					(thickness 0.15)
				)
				(justify left bottom mirror)
			)
		)
		(property "Value" "R_1k_0402"
			(at 0 -1.4 180)
			(layer "B.Fab")
			(effects
				(font
					(size 0.7 0.7)
					(thickness 0.15)
				)
				(justify left bottom mirror)
			)
		)
		(property "Description" "SMD Chip Resistor, 1 kohm, ± 1%, 63 mW, 0402 [1005 Metric], Thick Film, General Purpose"
			(at 0 0 0)
			(layer "F.Fab")
			(hide yes)
			(effects
				(font
					(size 1.27 1.27)
					(thickness 0.15)
				)
			)
		)
		(property "Author" "Antmicro"
			(at 0 0 0)
			(layer "B.Fab")
			(hide yes)
			(effects
				(font
					(size 1 1)
					(thickness 0.15)
				)
				(justify mirror)
			)
		)
		(property "License" "Apache-2.0"
			(at 0 0 0)
			(layer "B.Fab")
			(hide yes)
			(effects
				(font
					(size 1 1)
					(thickness 0.15)
				)
				(justify mirror)
			)
		)
		(property "MPN" "CR0402-FX-1001GLF"
			(at 0 0 0)
			(layer "B.Fab")
			(hide yes)
			(effects
				(font
					(size 1 1)
					(thickness 0.15)
				)
				(justify mirror)
			)
		)
		(property "Manufacturer" "Bourns"
			(at 0 0 0)
			(layer "B.Fab")
			(hide yes)
			(effects
				(font
					(size 1 1)
					(thickness 0.15)
				)
				(justify mirror)
			)
		)
		(property "Tolerance" "1%"
			(at 0 0 0)
			(layer "B.Fab")
			(hide yes)
			(effects
				(font
					(size 1 1)
					(thickness 0.15)
				)
				(justify mirror)
			)
		)
		(property "Val" "1k"
			(at 0 0 0)
			(layer "B.Fab")
			(hide yes)
			(effects
				(font
					(size 1 1)
					(thickness 0.15)
				)
				(justify mirror)
			)
		)
		(sheetname "User GPIO + LED + button + DIP switch")
		(sheetfile "user-gpio.kicad_sch")
		(attr smd)
		(fp_rect
			(start -0.925 0.47)
			(end 0.925 -0.47)
			(stroke
				(width 0.05)
				(type default)
			)
			(fill no)
			(layer "B.CrtYd")
		)
		(fp_rect
			(start -0.5 0.25)
			(end 0.5 -0.25)
			(stroke
				(width 0.15)
				(type solid)
			)
			(fill no)
			(layer "B.Fab")
		)
		(pad "1" smd roundrect
			(at -0.48 0)
			(size 0.59 0.64)
			(layers "B.Cu" "B.Mask" "B.Paste")
			(roundrect_rratio 0.25)
			(net 24 "+3V3")
			(pintype "passive")
		)
		(pad "2" smd roundrect
			(at 0.48 0)
			(size 0.59 0.64)
			(layers "B.Cu" "B.Mask" "B.Paste")
			(roundrect_rratio 0.25)
			(net 779 "Net-(D20-A)")
			(pintype "passive")
		)
	)
	(footprint "antmicro-footprints:C_0201"
		(layer "B.Cu")
		(at 188.000001 120.500001 180)
		(descr "Capacitor SMD 0201")
		(tags "capacitor SMD 0201")
		(property "Reference" "C150"
			(at 0.575001 -0.349999 0)
			(layer "B.SilkS")
			(effects
				(font
					(size 0.7 0.7)
					(thickness 0.15)
				)
				(justify left bottom mirror)
			)
		)
		(property "Value" "C_100n_0201"
			(at 0 -1.4 0)
			(layer "B.Fab")
			(effects
				(font
					(size 0.7 0.7)
					(thickness 0.15)
				)
				(justify left bottom mirror)
			)
		)
		(property "Description" "SMD Multilayer Ceramic Capacitor, 0.1 µF, 6.3 V, 0201 [0603 Metric], ± 10%, X6S, CC Series"
			(at 0 0 180)
			(layer "F.Fab")
			(hide yes)
			(effects
				(font
					(size 1.27 1.27)
					(thickness 0.15)
				)
			)
		)
		(property "Author" "Antmicro"
			(at 376.000002 241.000002 0)
			(layer "B.Fab")
			(hide yes)
			(effects
				(font
					(size 1 1)
					(thickness 0.15)
				)
				(justify mirror)
			)
		)
		(property "Dielectric" ""
			(at 376.000002 241.000002 0)
			(layer "B.Fab")
			(hide yes)
			(effects
				(font
					(size 1 1)
					(thickness 0.15)
				)
				(justify mirror)
			)
		)
		(property "License" "Apache-2.0"
			(at 376.000002 241.000002 0)
			(layer "B.Fab")
			(hide yes)
			(effects
				(font
					(size 1 1)
					(thickness 0.15)
				)
				(justify mirror)
			)
		)
		(property "MPN" "CC0201KRX6S5BB104"
			(at 376.000002 241.000002 0)
			(layer "B.Fab")
			(hide yes)
			(effects
				(font
					(size 1 1)
					(thickness 0.15)
				)
				(justify mirror)
			)
		)
		(property "Manufacturer" "YAGEO"
			(at 376.000002 241.000002 0)
			(layer "B.Fab")
			(hide yes)
			(effects
				(font
					(size 1 1)
					(thickness 0.15)
				)
				(justify mirror)
			)
		)
		(property "Val" "100n"
			(at 376.000002 241.000002 0)
			(layer "B.Fab")
			(hide yes)
			(effects
				(font
					(size 1 1)
					(thickness 0.15)
				)
				(justify mirror)
			)
		)
		(property "Voltage" ""
			(at 376.000002 241.000002 0)
			(layer "B.Fab")
			(hide yes)
			(effects
				(font
					(size 1 1)
					(thickness 0.15)
				)
				(justify mirror)
			)
		)
		(sheetname "FPGA supply")
		(sheetfile "fpga-supply.kicad_sch")
		(attr smd)
		(fp_rect
			(start -0.7 0.35)
			(end 0.7 -0.35)
			(stroke
				(width 0.05)
				(type default)
			)
			(fill no)
			(layer "B.CrtYd")
		)
		(fp_rect
			(start 0.3 -0.15)
			(end -0.301 0.149)
			(stroke
				(width 0.15)
				(type solid)
			)
			(fill no)
			(layer "B.Fab")
		)
		(pad "" smd roundrect
			(at -0.349 0.002 180)
			(size 0.318 0.36)
			(layers "B.Paste")
			(roundrect_rratio 0.25)
		)
		(pad "" smd roundrect
			(at 0.341 0.002 180)
			(size 0.318 0.36)
			(layers "B.Paste")
			(roundrect_rratio 0.25)
		)
		(pad "1" smd roundrect
			(at -0.321 0.002 180)
			(size 0.46 0.4)
			(layers "B.Cu" "B.Mask")
			(roundrect_rratio 0.25)
			(net 1 "GND")
			(pintype "passive")
		)
		(pad "2" smd roundrect
			(at 0.32 0.002 180)
			(size 0.46 0.4)
			(layers "B.Cu" "B.Mask")
			(roundrect_rratio 0.25)
			(net 8 "+1V2_MGTAVTT")
			(pintype "passive")
		)
	)
	(footprint "antmicro-footprints:C_0402_1005Metric"
		(layer "B.Cu")
		(at 194.85 132.225 180)
		(descr "Capacitor SMD 0402")
		(tags "capacitor SMD 0402")
		(property "Reference" "C114"
			(at -24.475 28.075 0)
			(layer "B.SilkS")
			(effects
				(font
					(size 0.7 0.7)
					(thickness 0.15)
				)
				(justify left bottom mirror)
			)
		)
		(property "Value" "C_100n_0402"
			(at 0 -1.169 0)
			(layer "B.Fab")
			(effects
				(font
					(size 0.7 0.7)
					(thickness 0.15)
				)
				(justify left bottom mirror)
			)
		)
		(property "Description" "SMD Multilayer Ceramic Capacitor, 0.1 µF, 50 V, 0402 [1005 Metric], ± 10%, X5R, GRM Series"
			(at 0 0 180)
			(layer "F.Fab")
			(hide yes)
			(effects
				(font
					(size 1.27 1.27)
					(thickness 0.15)
				)
			)
		)
		(property "Author" "Antmicro"
			(at 389.7 264.45 0)
			(layer "B.Fab")
			(hide yes)
			(effects
				(font
					(size 1 1)
					(thickness 0.15)
				)
				(justify mirror)
			)
		)
		(property "Dielectric" "X5R"
			(at 389.7 264.45 0)
			(layer "B.Fab")
			(hide yes)
			(effects
				(font
					(size 1 1)
					(thickness 0.15)
				)
				(justify mirror)
			)
		)
		(property "License" "Apache-2.0"
			(at 389.7 264.45 0)
			(layer "B.Fab")
			(hide yes)
			(effects
				(font
					(size 1 1)
					(thickness 0.15)
				)
				(justify mirror)
			)
		)
		(property "MPN" "GRM155R61H104KE14D"
			(at 389.7 264.45 0)
			(layer "B.Fab")
			(hide yes)
			(effects
				(font
					(size 1 1)
					(thickness 0.15)
				)
				(justify mirror)
			)
		)
		(property "Manufacturer" "Murata"
			(at 389.7 264.45 0)
			(layer "B.Fab")
			(hide yes)
			(effects
				(font
					(size 1 1)
					(thickness 0.15)
				)
				(justify mirror)
			)
		)
		(property "Val" "100n"
			(at 389.7 264.45 0)
			(layer "B.Fab")
			(hide yes)
			(effects
				(font
					(size 1 1)
					(thickness 0.15)
				)
				(justify mirror)
			)
		)
		(property "Voltage" "50V"
			(at 389.7 264.45 0)
			(layer "B.Fab")
			(hide yes)
			(effects
				(font
					(size 1 1)
					(thickness 0.15)
				)
				(justify mirror)
			)
		)
		(sheetname "FPGA supply")
		(sheetfile "fpga-supply.kicad_sch")
		(attr smd)
		(fp_rect
			(start -0.925 0.47)
			(end 0.925 -0.47)
			(stroke
				(width 0.05)
				(type default)
			)
			(fill no)
			(layer "B.CrtYd")
		)
		(fp_line
			(start 0.504 0.25)
			(end 0.504 -0.248)
			(stroke
				(width 0.15)
				(type solid)
			)
			(layer "B.Fab")
		)
		(fp_line
			(start 0.504 -0.248)
			(end -0.494 -0.248)
			(stroke
				(width 0.15)
				(type solid)
			)
			(layer "B.Fab")
		)
		(fp_line
			(start -0.494 0.25)
			(end 0.504 0.25)
			(stroke
				(width 0.15)
				(type solid)
			)
			(layer "B.Fab")
		)
		(fp_line
			(start -0.494 -0.248)
			(end -0.494 0.25)
			(stroke
				(width 0.15)
				(type solid)
			)
			(layer "B.Fab")
		)
		(pad "1" smd roundrect
			(at -0.48 0 180)
			(size 0.59 0.64)
			(layers "B.Cu" "B.Mask" "B.Paste")
			(roundrect_rratio 0.25)
			(net 1 "GND")
			(pintype "passive")
		)
		(pad "2" smd roundrect
			(at 0.48 0 180)
			(size 0.59 0.64)
			(layers "B.Cu" "B.Mask" "B.Paste")
			(roundrect_rratio 0.25)
			(net 650 "+1V0")
			(pintype "passive")
		)
	)
	(footprint "antmicro-footprints:C_0201"
		(layer "B.Cu")
		(at 201.5 132.05 180)
		(descr "Capacitor SMD 0201")
		(tags "capacitor SMD 0201")
		(property "Reference" "C65"
			(at -26.875 28.525 0)
			(layer "B.SilkS")
			(effects
				(font
					(size 0.7 0.7)
					(thickness 0.15)
				)
				(justify left bottom mirror)
			)
		)
		(property "Value" "C_100n_0201"
			(at 0 -1.4 0)
			(layer "B.Fab")
			(effects
				(font
					(size 0.7 0.7)
					(thickness 0.15)
				)
				(justify left bottom mirror)
			)
		)
		(property "Description" "SMD Multilayer Ceramic Capacitor, 0.1 µF, 6.3 V, 0201 [0603 Metric], ± 10%, X6S, CC Series"
			(at 0 0 180)
			(layer "F.Fab")
			(hide yes)
			(effects
				(font
					(size 1.27 1.27)
					(thickness 0.15)
				)
			)
		)
		(property "Author" "Antmicro"
			(at 403 264.1 0)
			(layer "B.Fab")
			(hide yes)
			(effects
				(font
					(size 1 1)
					(thickness 0.15)
				)
				(justify mirror)
			)
		)
		(property "Dielectric" ""
			(at 403 264.1 0)
			(layer "B.Fab")
			(hide yes)
			(effects
				(font
					(size 1 1)
					(thickness 0.15)
				)
				(justify mirror)
			)
		)
		(property "License" "Apache-2.0"
			(at 403 264.1 0)
			(layer "B.Fab")
			(hide yes)
			(effects
				(font
					(size 1 1)
					(thickness 0.15)
				)
				(justify mirror)
			)
		)
		(property "MPN" "CC0201KRX6S5BB104"
			(at 403 264.1 0)
			(layer "B.Fab")
			(hide yes)
			(effects
				(font
					(size 1 1)
					(thickness 0.15)
				)
				(justify mirror)
			)
		)
		(property "Manufacturer" "YAGEO"
			(at 403 264.1 0)
			(layer "B.Fab")
			(hide yes)
			(effects
				(font
					(size 1 1)
					(thickness 0.15)
				)
				(justify mirror)
			)
		)
		(property "Val" "100n"
			(at 403 264.1 0)
			(layer "B.Fab")
			(hide yes)
			(effects
				(font
					(size 1 1)
					(thickness 0.15)
				)
				(justify mirror)
			)
		)
		(property "Voltage" ""
			(at 403 264.1 0)
			(layer "B.Fab")
			(hide yes)
			(effects
				(font
					(size 1 1)
					(thickness 0.15)
				)
				(justify mirror)
			)
		)
		(sheetname "FPGA supply")
		(sheetfile "fpga-supply.kicad_sch")
		(attr smd)
		(fp_rect
			(start -0.7 0.35)
			(end 0.7 -0.35)
			(stroke
				(width 0.05)
				(type default)
			)
			(fill no)
			(layer "B.CrtYd")
		)
		(fp_rect
			(start 0.3 -0.15)
			(end -0.301 0.149)
			(stroke
				(width 0.15)
				(type solid)
			)
			(fill no)
			(layer "B.Fab")
		)
		(pad "" smd roundrect
			(at -0.349 0.002 180)
			(size 0.318 0.36)
			(layers "B.Paste")
			(roundrect_rratio 0.25)
		)
		(pad "" smd roundrect
			(at 0.341 0.002 180)
			(size 0.318 0.36)
			(layers "B.Paste")
			(roundrect_rratio 0.25)
		)
		(pad "1" smd roundrect
			(at -0.321 0.002 180)
			(size 0.46 0.4)
			(layers "B.Cu" "B.Mask")
			(roundrect_rratio 0.25)
			(net 1 "GND")
			(pintype "passive")
		)
		(pad "2" smd roundrect
			(at 0.32 0.002 180)
			(size 0.46 0.4)
			(layers "B.Cu" "B.Mask")
			(roundrect_rratio 0.25)
			(net 650 "+1V0")
			(pintype "passive")
		)
	)
)
